# S9S_MB_2U (Grand Teton) — schematic netlist excerpt (pin names and nets, part order shuffled) for the footprints in the layout excerpt that follows; sources: Cadence DE-HDL packaged netlist, KiCad conversion of 03242023_DA0F0TMBIJ0_F0T_Motherboard_J_brd_V01_OCP.brd

R2582  Q_RES  0 5% CHIP  pkg 0402LF  page 296 : A = SMB_VR_3V3AUX_SDA_R ; B = SMB_DIO_PVCCD_HV_CPU1
C1901  Q_CAP  0.01UF 50V 10% X7R  pkg C0402  page 217 : A = P3V3_AUX_FPGA_VCCIO0 ; B = GND

(kicad_pcb
	(version 20260206)
	(generator "pcbnew")
	(generator_version "10.0")
	(general
		(thickness 1.6)
		(legacy_teardrops no)
	)
	(paper "A4")
	(title_block
		(title "03242023_DA0F0TMBIJ0_F0T_Motherboard_J_brd_V01_OCP.brd")
		(comment 1 "Grand Teton / footprints 6020-6021 of 6105")
	)
	(layers
		(0 "F.Cu" signal "TOP")
		(4 "In1.Cu" signal "GND")
		(6 "In2.Cu" signal "IN1")
		(8 "In3.Cu" signal "GND1")
		(10 "In4.Cu" signal "IN2")
		(12 "In5.Cu" signal "GND2")
		(14 "In6.Cu" signal "IN3")
		(16 "In7.Cu" signal "GND3")
		(18 "In8.Cu" signal "VCC")
		(20 "In9.Cu" signal "VCC1")
		(22 "In10.Cu" signal "GND4")
		(24 "In11.Cu" signal "IN4")
		(26 "In12.Cu" signal "GND5")
		(28 "In13.Cu" signal "IN5")
		(30 "In14.Cu" signal "GND6")
		(32 "In15.Cu" signal "IN6")
		(34 "In16.Cu" signal "GND7")
		(2 "B.Cu" signal "BOTTOM")
		(9 "F.Adhes" user "F.Adhesive")
		(11 "B.Adhes" user "B.Adhesive")
		(13 "F.Paste" user "Package Geometry/Pastemask Top")
		(15 "B.Paste" user "Package Geometry/Pastemask Bottom")
		(5 "F.SilkS" user "Ref Des/Silkscreen Top")
		(7 "B.SilkS" user "Ref Des/Silkscreen Bottom")
		(1 "F.Mask" user "Board Geometry/Soldermask Top")
		(3 "B.Mask" user "Board Geometry/Soldermask Bottom")
		(17 "Dwgs.User" user "User.Drawings")
		(19 "Cmts.User" user "User.Comments")
		(21 "Eco1.User" user "User.Eco1")
		(23 "Eco2.User" user "User.Eco2")
		(25 "Edge.Cuts" user "Board Geometry/Outline")
		(27 "Margin" user)
		(31 "F.CrtYd" user "Package Geometry/Place Bound Top")
		(29 "B.CrtYd" user "Package Geometry/Place Bound Bottom")
		(35 "F.Fab" user "Ref Des/Assembly Top")
		(33 "B.Fab" user "Ref Des/Assembly Bottom")
	)
	(footprint ""
		(layer "B.Cu")
		(at 170.555666 -109.775498)
		(property "Reference" "C1901"
			(at 0 0 0)
			(layer "B.SilkS")
			(hide yes)
			(effects
				(font
					(size 1.27 1.27)
				)
				(justify mirror)
			)
		)
		(property "Value" ""
			(at 0 0 0)
			(layer "B.Fab")
			(effects
				(font
					(size 1.27 1.27)
				)
				(justify mirror)
			)
		)
		(duplicate_pad_numbers_are_jumpers no)
		(fp_line
			(start -0.69215 -0.2921)
			(end -0.69215 0.2921)
			(stroke
				(width 0.1524)
				(type default)
			)
			(layer "B.SilkS")
		)
		(fp_line
			(start -0.69215 0.2921)
			(end 0.69215 0.2921)
			(stroke
				(width 0.1524)
				(type default)
			)
			(layer "B.SilkS")
		)
		(fp_line
			(start 0.69215 -0.2921)
			(end -0.69215 -0.2921)
			(stroke
				(width 0.1524)
				(type default)
			)
			(layer "B.SilkS")
		)
		(fp_line
			(start 0.69215 0.2921)
			(end 0.69215 -0.2921)
			(stroke
				(width 0.1524)
				(type default)
			)
			(layer "B.SilkS")
		)
		(fp_line
			(start -0.51435 -0.2794)
			(end -0.51435 0.2794)
			(stroke
				(width 0.1)
				(type default)
			)
			(layer "B.Fab")
		)
		(fp_line
			(start -0.51435 0.2794)
			(end 0.51435 0.2794)
			(stroke
				(width 0.1)
				(type default)
			)
			(layer "B.Fab")
		)
		(fp_line
			(start 0.51435 -0.2794)
			(end -0.51435 -0.2794)
			(stroke
				(width 0.1)
				(type default)
			)
			(layer "B.Fab")
		)
		(fp_line
			(start 0.51435 0.2794)
			(end 0.51435 -0.2794)
			(stroke
				(width 0.1)
				(type default)
			)
			(layer "B.Fab")
		)
		(pad "1" smd circle
			(at 0.40005 0 180)
			(size 0 0)
			(layers "B.Cu" "B.Mask" "B.Paste")
			(net "P3V3_AUX_FPGA_VCCIO0")
		)
		(pad "2" smd circle
			(at -0.40005 0 180)
			(size 0 0)
			(layers "B.Cu" "B.Mask" "B.Paste")
			(net "GND")
		)
		(zone
			(layer "B.Cu")
			(hatch none 0.5)
			(connect_pads
				(clearance 0)
			)
			(min_thickness 0.25)
			(keepout
				(tracks not_allowed)
				(vias allowed)
				(pads allowed)
				(copperpour not_allowed)
				(footprints allowed)
			)
			(placement
				(enabled no)
				(sheetname "")
			)
			(fill
				(thermal_gap 0.5)
				(thermal_bridge_width 0.5)
				(island_removal_mode 0)
			)
			(polygon
				(pts
					(xy 170.746166 -109.687868) (xy 170.654726 -109.629702) (xy 170.455336 -109.629702) (xy 170.365166 -109.687868)
					(xy 170.365166 -109.863128) (xy 170.455336 -109.921548) (xy 170.654726 -109.921548) (xy 170.746166 -109.863382)
				)
			)
		)
	)
	(footprint ""
		(layer "B.Cu")
		(at 22.989032 -172.181774 180)
		(property "Reference" "R2582"
			(at 0 0 0)
			(layer "B.SilkS")
			(hide yes)
			(effects
				(font
					(size 1.27 1.27)
				)
				(justify mirror)
			)
		)
		(property "Value" ""
			(at 0 0 0)
			(layer "B.Fab")
			(effects
				(font
					(size 1.27 1.27)
				)
				(justify mirror)
			)
		)
		(duplicate_pad_numbers_are_jumpers no)
		(fp_line
			(start 0.7874 0.4064)
			(end 0.7874 -0.4064)
			(stroke
				(width 0.1524)
				(type default)
			)
			(layer "B.SilkS")
		)
		(fp_line
			(start 0.7874 -0.4064)
			(end -0.7874 -0.4064)
			(stroke
				(width 0.1524)
				(type default)
			)
			(layer "B.SilkS")
		)
		(fp_line
			(start -0.7874 0.4064)
			(end 0.7874 0.4064)
			(stroke
				(width 0.1524)
				(type default)
			)
			(layer "B.SilkS")
		)
		(fp_line
			(start -0.7874 -0.4064)
			(end -0.7874 0.4064)
			(stroke
				(width 0.1524)
				(type default)
			)
			(layer "B.SilkS")
		)
		(fp_line
			(start 0.67945 0.3048)
			(end 0.67945 -0.305054)
			(stroke
				(width 0.1)
				(type default)
			)
			(layer "B.Fab")
		)
		(fp_line
			(start 0.67945 -0.305054)
			(end 0.12065 -0.305054)
			(stroke
				(width 0.1)
				(type default)
			)
			(layer "B.Fab")
		)
		(fp_line
			(start 0.12065 0.3048)
			(end 0.67945 0.3048)
			(stroke
				(width 0.1)
				(type default)
			)
			(layer "B.Fab")
		)
		(fp_line
			(start 0.12065 0.2794)
			(end 0.12065 0.3048)
			(stroke
				(width 0.1)
				(type default)
			)
			(layer "B.Fab")
		)
		(fp_line
			(start 0.12065 -0.2794)
			(end -0.12065 -0.2794)
			(stroke
				(width 0.1)
				(type default)
			)
			(layer "B.Fab")
		)
		(fp_line
			(start 0.12065 -0.305054)
			(end 0.12065 -0.2794)
			(stroke
				(width 0.1)
				(type default)
			)
			(layer "B.Fab")
		)
		(fp_line
			(start -0.120396 0.3048)
			(end -0.120396 0.2794)
			(stroke
				(width 0.1)
				(type default)
			)
			(layer "B.Fab")
		)
		(fp_line
			(start -0.120396 0.2794)
			(end 0.12065 0.2794)
			(stroke
				(width 0.1)
				(type default)
			)
			(layer "B.Fab")
		)
		(fp_line
			(start -0.12065 -0.2794)
			(end -0.12065 -0.3048)
			(stroke
				(width 0.1)
				(type default)
			)
			(layer "B.Fab")
		)
		(fp_line
			(start -0.12065 -0.3048)
			(end -0.67945 -0.3048)
			(stroke
				(width 0.1)
				(type default)
			)
			(layer "B.Fab")
		)
		(fp_line
			(start -0.67945 0.3048)
			(end -0.120396 0.3048)
			(stroke
				(width 0.1)
				(type default)
			)
			(layer "B.Fab")
		)
		(fp_line
			(start -0.67945 -0.3048)
			(end -0.67945 0.3048)
			(stroke
				(width 0.1)
				(type default)
			)
			(layer "B.Fab")
		)
		(pad "1" smd circle
			(at 0.40005 0)
			(size 0 0)
			(layers "B.Cu" "B.Mask" "B.Paste")
			(net "SMB_VR_3V3AUX_SDA_R")
		)
		(pad "2" smd circle
			(at -0.40005 0)
			(size 0 0)
			(layers "B.Cu" "B.Mask" "B.Paste")
			(net "SMB_DIO_PVCCD_HV_CPU1")
		)
	)
)
